# T6G (Grand Teton) — schematic netlist excerpt (pin names and nets, part order shuffled) for the footprints in the layout excerpt that follows; sources: Cadence DE-HDL packaged netlist, KiCad conversion of 04192023_DAF0TMB3IC0_F0TG_MB_C_brd_V02_OCP.brd

C2447  Q_CAP  22UF 4V 20% X6S  pkg C0402  page 74 : A = PVDDCR_SOC_P1 ; B = GND
R767  Q_RES  35.7K 1% CHIP  pkg 0402LF  page 95 : A = PD_CHJ_CPU0_DIMM_SAA ; B = GND
R831  Q_RES  0 5% CHIP  pkg 0201LF  page 185 : A = SMB_RT_CPU0_P3_ROM_MUX_2D_R_SCL ; B = SMB_RT_CPU0_P3_ROM_MUX_2D_SCL

(kicad_pcb
	(version 20260206)
	(generator "pcbnew")
	(generator_version "10.0")
	(general
		(thickness 1.6)
		(legacy_teardrops no)
	)
	(paper "A4")
	(title_block
		(title "04192023_DAF0TMB3IC0_F0TG_MB_C_brd_V02_OCP.brd")
		(comment 1 "Grand Teton / footprints 5368-5370 of 8354")
	)
	(layers
		(0 "F.Cu" signal "TOP")
		(4 "In1.Cu" signal "GND")
		(6 "In2.Cu" signal "IN1")
		(8 "In3.Cu" signal "GND1")
		(10 "In4.Cu" signal "IN2")
		(12 "In5.Cu" signal "GND2")
		(14 "In6.Cu" signal "IN3")
		(16 "In7.Cu" signal "GND3")
		(18 "In8.Cu" signal "VCC")
		(20 "In9.Cu" signal "VCC1")
		(22 "In10.Cu" signal "GND4")
		(24 "In11.Cu" signal "IN4")
		(26 "In12.Cu" signal "GND5")
		(28 "In13.Cu" signal "IN5")
		(30 "In14.Cu" signal "GND6")
		(32 "In15.Cu" signal "IN6")
		(34 "In16.Cu" signal "GND7")
		(2 "B.Cu" signal "BOTTOM")
		(9 "F.Adhes" user "F.Adhesive")
		(11 "B.Adhes" user "B.Adhesive")
		(13 "F.Paste" user "Package Geometry/Pastemask Top")
		(15 "B.Paste" user "Package Geometry/Pastemask Bottom")
		(5 "F.SilkS" user "Ref Des/Silkscreen Top")
		(7 "B.SilkS" user "Ref Des/Silkscreen Bottom")
		(1 "F.Mask" user "Board Geometry/Soldermask Top")
		(3 "B.Mask" user "Board Geometry/Soldermask Bottom")
		(17 "Dwgs.User" user "User.Drawings")
		(19 "Cmts.User" user "User.Comments")
		(21 "Eco1.User" user "User.Eco1")
		(23 "Eco2.User" user "User.Eco2")
		(25 "Edge.Cuts" user "Board Geometry/Outline")
		(27 "Margin" user)
		(31 "F.CrtYd" user "Package Geometry/Place Bound Top")
		(29 "B.CrtYd" user "Package Geometry/Place Bound Bottom")
		(35 "F.Fab" user "Ref Des/Assembly Top")
		(33 "B.Fab" user "Ref Des/Assembly Bottom")
	)
	(footprint ""
		(layer "B.Cu")
		(at 125.389386 -255.845564)
		(property "Reference" "C2447"
			(at 0 0 0)
			(layer "B.SilkS")
			(hide yes)
			(effects
				(font
					(size 1.27 1.27)
				)
				(justify mirror)
			)
		)
		(property "Value" ""
			(at 0 0 0)
			(layer "B.Fab")
			(effects
				(font
					(size 1.27 1.27)
				)
				(justify mirror)
			)
		)
		(duplicate_pad_numbers_are_jumpers no)
		(fp_line
			(start -0.7874 -0.4064)
			(end -0.7874 0.4064)
			(stroke
				(width 0.1524)
				(type default)
			)
			(layer "B.SilkS")
		)
		(fp_line
			(start -0.7874 0.4064)
			(end 0.7874 0.4064)
			(stroke
				(width 0.1524)
				(type default)
			)
			(layer "B.SilkS")
		)
		(fp_line
			(start 0.7874 -0.4064)
			(end -0.7874 -0.4064)
			(stroke
				(width 0.1524)
				(type default)
			)
			(layer "B.SilkS")
		)
		(fp_line
			(start 0.7874 0.4064)
			(end 0.7874 -0.4064)
			(stroke
				(width 0.1524)
				(type default)
			)
			(layer "B.SilkS")
		)
		(fp_line
			(start -0.67945 -0.3048)
			(end -0.67945 0.3048)
			(stroke
				(width 0.1)
				(type default)
			)
			(layer "B.Fab")
		)
		(fp_line
			(start -0.67945 0.3048)
			(end -0.120396 0.3048)
			(stroke
				(width 0.1)
				(type default)
			)
			(layer "B.Fab")
		)
		(fp_line
			(start -0.12065 -0.3048)
			(end -0.67945 -0.3048)
			(stroke
				(width 0.1)
				(type default)
			)
			(layer "B.Fab")
		)
		(fp_line
			(start -0.12065 -0.2794)
			(end -0.12065 -0.3048)
			(stroke
				(width 0.1)
				(type default)
			)
			(layer "B.Fab")
		)
		(fp_line
			(start -0.120396 0.2794)
			(end 0.12065 0.2794)
			(stroke
				(width 0.1)
				(type default)
			)
			(layer "B.Fab")
		)
		(fp_line
			(start -0.120396 0.3048)
			(end -0.120396 0.2794)
			(stroke
				(width 0.1)
				(type default)
			)
			(layer "B.Fab")
		)
		(fp_line
			(start 0.12065 -0.305054)
			(end 0.12065 -0.2794)
			(stroke
				(width 0.1)
				(type default)
			)
			(layer "B.Fab")
		)
		(fp_line
			(start 0.12065 -0.2794)
			(end -0.12065 -0.2794)
			(stroke
				(width 0.1)
				(type default)
			)
			(layer "B.Fab")
		)
		(fp_line
			(start 0.12065 0.2794)
			(end 0.12065 0.3048)
			(stroke
				(width 0.1)
				(type default)
			)
			(layer "B.Fab")
		)
		(fp_line
			(start 0.12065 0.3048)
			(end 0.67945 0.3048)
			(stroke
				(width 0.1)
				(type default)
			)
			(layer "B.Fab")
		)
		(fp_line
			(start 0.67945 -0.305054)
			(end 0.12065 -0.305054)
			(stroke
				(width 0.1)
				(type default)
			)
			(layer "B.Fab")
		)
		(fp_line
			(start 0.67945 0.3048)
			(end 0.67945 -0.305054)
			(stroke
				(width 0.1)
				(type default)
			)
			(layer "B.Fab")
		)
		(pad "1" smd circle
			(at 0.40005 0 180)
			(size 0 0)
			(layers "B.Cu" "B.Mask" "B.Paste")
			(net "PVDDCR_SOC_P1")
		)
		(pad "2" smd circle
			(at -0.40005 0 180)
			(size 0 0)
			(layers "B.Cu" "B.Mask" "B.Paste")
			(net "GND")
		)
	)
	(footprint ""
		(layer "B.Cu")
		(at 435.755796 -194.88531 180)
		(property "Reference" "R767"
			(at 0 0 0)
			(layer "B.SilkS")
			(hide yes)
			(effects
				(font
					(size 1.27 1.27)
				)
				(justify mirror)
			)
		)
		(property "Value" ""
			(at 0 0 0)
			(layer "B.Fab")
			(effects
				(font
					(size 1.27 1.27)
				)
				(justify mirror)
			)
		)
		(duplicate_pad_numbers_are_jumpers no)
		(fp_line
			(start 0.7874 0.4064)
			(end 0.7874 -0.4064)
			(stroke
				(width 0.1524)
				(type default)
			)
			(layer "B.SilkS")
		)
		(fp_line
			(start 0.7874 -0.4064)
			(end -0.7874 -0.4064)
			(stroke
				(width 0.1524)
				(type default)
			)
			(layer "B.SilkS")
		)
		(fp_line
			(start -0.7874 0.4064)
			(end 0.7874 0.4064)
			(stroke
				(width 0.1524)
				(type default)
			)
			(layer "B.SilkS")
		)
		(fp_line
			(start -0.7874 -0.4064)
			(end -0.7874 0.4064)
			(stroke
				(width 0.1524)
				(type default)
			)
			(layer "B.SilkS")
		)
		(fp_line
			(start 0.67945 0.3048)
			(end 0.67945 -0.305054)
			(stroke
				(width 0.1)
				(type default)
			)
			(layer "B.Fab")
		)
		(fp_line
			(start 0.67945 -0.305054)
			(end 0.12065 -0.305054)
			(stroke
				(width 0.1)
				(type default)
			)
			(layer "B.Fab")
		)
		(fp_line
			(start 0.12065 0.3048)
			(end 0.67945 0.3048)
			(stroke
				(width 0.1)
				(type default)
			)
			(layer "B.Fab")
		)
		(fp_line
			(start 0.12065 0.2794)
			(end 0.12065 0.3048)
			(stroke
				(width 0.1)
				(type default)
			)
			(layer "B.Fab")
		)
		(fp_line
			(start 0.12065 -0.2794)
			(end -0.12065 -0.2794)
			(stroke
				(width 0.1)
				(type default)
			)
			(layer "B.Fab")
		)
		(fp_line
			(start 0.12065 -0.305054)
			(end 0.12065 -0.2794)
			(stroke
				(width 0.1)
				(type default)
			)
			(layer "B.Fab")
		)
		(fp_line
			(start -0.120396 0.3048)
			(end -0.120396 0.2794)
			(stroke
				(width 0.1)
				(type default)
			)
			(layer "B.Fab")
		)
		(fp_line
			(start -0.120396 0.2794)
			(end 0.12065 0.2794)
			(stroke
				(width 0.1)
				(type default)
			)
			(layer "B.Fab")
		)
		(fp_line
			(start -0.12065 -0.2794)
			(end -0.12065 -0.3048)
			(stroke
				(width 0.1)
				(type default)
			)
			(layer "B.Fab")
		)
		(fp_line
			(start -0.12065 -0.3048)
			(end -0.67945 -0.3048)
			(stroke
				(width 0.1)
				(type default)
			)
			(layer "B.Fab")
		)
		(fp_line
			(start -0.67945 0.3048)
			(end -0.120396 0.3048)
			(stroke
				(width 0.1)
				(type default)
			)
			(layer "B.Fab")
		)
		(fp_line
			(start -0.67945 -0.3048)
			(end -0.67945 0.3048)
			(stroke
				(width 0.1)
				(type default)
			)
			(layer "B.Fab")
		)
		(pad "1" smd circle
			(at 0.40005 0)
			(size 0 0)
			(layers "B.Cu" "B.Mask" "B.Paste")
			(net "PD_CHJ_CPU0_DIMM_SAA")
		)
		(pad "2" smd circle
			(at -0.40005 0)
			(size 0 0)
			(layers "B.Cu" "B.Mask" "B.Paste")
			(net "GND")
		)
	)
	(footprint ""
		(layer "B.Cu")
		(at 255.905 -336.25536 180)
		(property "Reference" "R831"
			(at 0 0 0)
			(layer "B.SilkS")
			(hide yes)
			(effects
				(font
					(size 1.27 1.27)
				)
				(justify mirror)
			)
		)
		(property "Value" ""
			(at 0 0 0)
			(layer "B.Fab")
			(effects
				(font
					(size 1.27 1.27)
				)
				(justify mirror)
			)
		)
		(duplicate_pad_numbers_are_jumpers no)
		(fp_line
			(start 0.32512 0.175006)
			(end 0.32512 -0.175006)
			(stroke
				(width 0.1)
				(type default)
			)
			(layer "B.Fab")
		)
		(fp_line
			(start 0.32512 -0.175006)
			(end -0.32512 -0.175006)
			(stroke
				(width 0.1)
				(type default)
			)
			(layer "B.Fab")
		)
		(fp_line
			(start -0.32512 0.175006)
			(end 0.32512 0.175006)
			(stroke
				(width 0.1)
				(type default)
			)
			(layer "B.Fab")
		)
		(fp_line
			(start -0.32512 -0.175006)
			(end -0.32512 0.175006)
			(stroke
				(width 0.1)
				(type default)
			)
			(layer "B.Fab")
		)
		(pad "1" smd rect
			(at 0.2667 0)
			(size 0.3048 0.381)
			(layers "B.Cu" "B.Mask" "B.Paste")
			(net "SMB_RT_CPU0_P3_ROM_MUX_2D_R_SCL")
		)
		(pad "2" smd rect
			(at -0.2667 0 180)
			(size 0.3048 0.381)
			(layers "B.Cu" "B.Mask" "B.Paste")
			(net "SMB_RT_CPU0_P3_ROM_MUX_2D_SCL")
		)
	)
)
